# T6G (Grand Teton) — schematic netlist excerpt (pin names and nets, part order shuffled) for the footprints in the layout excerpt that follows; sources: Cadence DE-HDL packaged netlist, KiCad conversion of 04192023_DAF0TMB3IC0_F0TG_MB_C_brd_V02_OCP.brd

PR3921  Q_RES  0 5% CHIP  pkg 0402LF  page 263 : A = HSC_D_OC_2 ; B = HSC_D_OC_R
PL57  Q_INDUCTOR  1.0UH/18A IND  pkg SMLF  page 226 : \1\ = SW_PVDD18_S5_P1_SW ; \2\ = PVDD18_S5_P1
C6527  Q_CAP_DIFFBUS  DIFF BUS_0.22UF 6.3V 20% X6S  pkg C0201  page 275 : \1\ = P5E_CPU0_P0_TX_BUF_C_DP<13> ; \2\ = P5E_CPU0_P0_TX_BUF_DP<13>

(kicad_pcb
	(version 20260206)
	(generator "pcbnew")
	(generator_version "10.0")
	(general
		(thickness 1.6)
		(legacy_teardrops no)
	)
	(paper "A4")
	(title_block
		(title "04192023_DAF0TMB3IC0_F0TG_MB_C_brd_V02_OCP.brd")
		(comment 1 "Grand Teton / footprints 1530-1532 of 8354")
	)
	(layers
		(0 "F.Cu" signal "TOP")
		(4 "In1.Cu" signal "GND")
		(6 "In2.Cu" signal "IN1")
		(8 "In3.Cu" signal "GND1")
		(10 "In4.Cu" signal "IN2")
		(12 "In5.Cu" signal "GND2")
		(14 "In6.Cu" signal "IN3")
		(16 "In7.Cu" signal "GND3")
		(18 "In8.Cu" signal "VCC")
		(20 "In9.Cu" signal "VCC1")
		(22 "In10.Cu" signal "GND4")
		(24 "In11.Cu" signal "IN4")
		(26 "In12.Cu" signal "GND5")
		(28 "In13.Cu" signal "IN5")
		(30 "In14.Cu" signal "GND6")
		(32 "In15.Cu" signal "IN6")
		(34 "In16.Cu" signal "GND7")
		(2 "B.Cu" signal "BOTTOM")
		(9 "F.Adhes" user "F.Adhesive")
		(11 "B.Adhes" user "B.Adhesive")
		(13 "F.Paste" user "Package Geometry/Pastemask Top")
		(15 "B.Paste" user "Package Geometry/Pastemask Bottom")
		(5 "F.SilkS" user "Ref Des/Silkscreen Top")
		(7 "B.SilkS" user "Ref Des/Silkscreen Bottom")
		(1 "F.Mask" user "Board Geometry/Soldermask Top")
		(3 "B.Mask" user "Board Geometry/Soldermask Bottom")
		(17 "Dwgs.User" user "User.Drawings")
		(19 "Cmts.User" user "User.Comments")
		(21 "Eco1.User" user "User.Eco1")
		(23 "Eco2.User" user "User.Eco2")
		(25 "Edge.Cuts" user "Board Geometry/Outline")
		(27 "Margin" user)
		(31 "F.CrtYd" user "Package Geometry/Place Bound Top")
		(29 "B.CrtYd" user "Package Geometry/Place Bound Bottom")
		(35 "F.Fab" user "Ref Des/Assembly Top")
		(33 "B.Fab" user "Ref Des/Assembly Bottom")
	)
	(footprint ""
		(layer "F.Cu")
		(at 60.012834 -150.979632 180)
		(property "Reference" "PL57"
			(at -1.85674 -6.476746 0)
			(unlocked yes)
			(layer "F.SilkS")
			(effects
				(font
					(size 0.7874 0.5842)
					(thickness 0.1524)
				)
				(justify left)
			)
		)
		(property "Value" ""
			(at 0 0 180)
			(layer "F.Fab")
			(effects
				(font
					(size 1.27 1.27)
				)
			)
		)
		(duplicate_pad_numbers_are_jumpers no)
		(fp_line
			(start 5.1054 5.100066)
			(end 5.1054 1.8796)
			(stroke
				(width 0.1524)
				(type default)
			)
			(layer "F.SilkS")
		)
		(fp_line
			(start 5.1054 -1.8796)
			(end 5.1054 -5.100066)
			(stroke
				(width 0.1524)
				(type default)
			)
			(layer "F.SilkS")
		)
		(fp_line
			(start 5.1054 -5.100066)
			(end -5.1054 -5.100066)
			(stroke
				(width 0.1524)
				(type default)
			)
			(layer "F.SilkS")
		)
		(fp_line
			(start -5.1054 5.100066)
			(end 5.1054 5.100066)
			(stroke
				(width 0.1524)
				(type default)
			)
			(layer "F.SilkS")
		)
		(fp_line
			(start -5.1054 1.8796)
			(end -5.1054 5.100066)
			(stroke
				(width 0.1524)
				(type default)
			)
			(layer "F.SilkS")
		)
		(fp_line
			(start -5.1054 -5.100066)
			(end -5.1054 -1.8796)
			(stroke
				(width 0.1524)
				(type default)
			)
			(layer "F.SilkS")
		)
		(fp_line
			(start 5.1054 5.100066)
			(end -5.1054 5.100066)
			(stroke
				(width 0.1)
				(type default)
			)
			(layer "F.Fab")
		)
		(fp_line
			(start 5.1054 -5.100066)
			(end 5.1054 5.100066)
			(stroke
				(width 0.1)
				(type default)
			)
			(layer "F.Fab")
		)
		(fp_line
			(start -5.1054 5.100066)
			(end -5.1054 -5.100066)
			(stroke
				(width 0.1)
				(type default)
			)
			(layer "F.Fab")
		)
		(fp_line
			(start -5.1054 -5.100066)
			(end 5.1054 -5.100066)
			(stroke
				(width 0.1)
				(type default)
			)
			(layer "F.Fab")
		)
		(pad "1" smd rect
			(at -3.999992 0 180)
			(size 3.5052 3.5052)
			(layers "F.Cu" "F.Mask" "F.Paste")
			(net "SW_PVDD18_S5_P1_SW")
		)
		(pad "2" smd rect
			(at 3.999992 0 180)
			(size 3.5052 3.5052)
			(layers "F.Cu" "F.Mask" "F.Paste")
			(net "PVDD18_S5_P1")
		)
	)
	(footprint ""
		(layer "F.Cu")
		(at 215.4301 -399.956782)
		(property "Reference" "PR3921"
			(at 0 0 0)
			(layer "F.SilkS")
			(hide yes)
			(effects
				(font
					(size 1.27 1.27)
				)
			)
		)
		(property "Value" ""
			(at 0 0 0)
			(layer "F.Fab")
			(effects
				(font
					(size 1.27 1.27)
				)
			)
		)
		(duplicate_pad_numbers_are_jumpers no)
		(fp_line
			(start -0.7874 -0.4064)
			(end 0.7874 -0.4064)
			(stroke
				(width 0.1524)
				(type default)
			)
			(layer "F.SilkS")
		)
		(fp_line
			(start -0.7874 0.4064)
			(end -0.7874 -0.4064)
			(stroke
				(width 0.1524)
				(type default)
			)
			(layer "F.SilkS")
		)
		(fp_line
			(start 0.7874 -0.4064)
			(end 0.7874 0.4064)
			(stroke
				(width 0.1524)
				(type default)
			)
			(layer "F.SilkS")
		)
		(fp_line
			(start 0.7874 0.4064)
			(end -0.7874 0.4064)
			(stroke
				(width 0.1524)
				(type default)
			)
			(layer "F.SilkS")
		)
		(fp_line
			(start -0.67945 -0.305054)
			(end -0.12065 -0.305054)
			(stroke
				(width 0.1)
				(type default)
			)
			(layer "F.Fab")
		)
		(fp_line
			(start -0.67945 0.3048)
			(end -0.67945 -0.305054)
			(stroke
				(width 0.1)
				(type default)
			)
			(layer "F.Fab")
		)
		(fp_line
			(start -0.12065 -0.305054)
			(end -0.12065 -0.2794)
			(stroke
				(width 0.1)
				(type default)
			)
			(layer "F.Fab")
		)
		(fp_line
			(start -0.12065 -0.2794)
			(end 0.12065 -0.2794)
			(stroke
				(width 0.1)
				(type default)
			)
			(layer "F.Fab")
		)
		(fp_line
			(start -0.12065 0.2794)
			(end -0.12065 0.3048)
			(stroke
				(width 0.1)
				(type default)
			)
			(layer "F.Fab")
		)
		(fp_line
			(start -0.12065 0.3048)
			(end -0.67945 0.3048)
			(stroke
				(width 0.1)
				(type default)
			)
			(layer "F.Fab")
		)
		(fp_line
			(start 0.120396 0.2794)
			(end -0.12065 0.2794)
			(stroke
				(width 0.1)
				(type default)
			)
			(layer "F.Fab")
		)
		(fp_line
			(start 0.120396 0.3048)
			(end 0.120396 0.2794)
			(stroke
				(width 0.1)
				(type default)
			)
			(layer "F.Fab")
		)
		(fp_line
			(start 0.12065 -0.3048)
			(end 0.67945 -0.3048)
			(stroke
				(width 0.1)
				(type default)
			)
			(layer "F.Fab")
		)
		(fp_line
			(start 0.12065 -0.2794)
			(end 0.12065 -0.3048)
			(stroke
				(width 0.1)
				(type default)
			)
			(layer "F.Fab")
		)
		(fp_line
			(start 0.67945 -0.3048)
			(end 0.67945 0.3048)
			(stroke
				(width 0.1)
				(type default)
			)
			(layer "F.Fab")
		)
		(fp_line
			(start 0.67945 0.3048)
			(end 0.120396 0.3048)
			(stroke
				(width 0.1)
				(type default)
			)
			(layer "F.Fab")
		)
		(pad "1" smd circle
			(at -0.40005 0)
			(size 0 0)
			(layers "F.Cu" "F.Mask" "F.Paste")
			(net "HSC_D_OC_2")
		)
		(pad "2" smd circle
			(at 0.40005 0)
			(size 0 0)
			(layers "F.Cu" "F.Mask" "F.Paste")
			(net "HSC_D_OC_R")
		)
	)
	(footprint ""
		(layer "F.Cu")
		(at 344.505026 -416.899344 -90)
		(property "Reference" "C6527"
			(at 0 0 270)
			(layer "F.SilkS")
			(hide yes)
			(effects
				(font
					(size 1.27 1.27)
				)
			)
		)
		(property "Value" ""
			(at 0 0 270)
			(layer "F.Fab")
			(effects
				(font
					(size 1.27 1.27)
				)
			)
		)
		(duplicate_pad_numbers_are_jumpers no)
		(fp_line
			(start -0.299974 0.150114)
			(end -0.299974 -0.150114)
			(stroke
				(width 0.1)
				(type default)
			)
			(layer "F.Fab")
		)
		(fp_line
			(start 0.299974 0.150114)
			(end -0.299974 0.150114)
			(stroke
				(width 0.1)
				(type default)
			)
			(layer "F.Fab")
		)
		(fp_line
			(start -0.299974 -0.150114)
			(end 0.299974 -0.150114)
			(stroke
				(width 0.1)
				(type default)
			)
			(layer "F.Fab")
		)
		(fp_line
			(start 0.299974 -0.150114)
			(end 0.299974 0.150114)
			(stroke
				(width 0.1)
				(type default)
			)
			(layer "F.Fab")
		)
		(pad "1" smd rect
			(at -0.2667 0 270)
			(size 0.3048 0.381)
			(layers "F.Cu" "F.Mask" "F.Paste")
			(net "P5E_CPU0_P0_TX_BUF_C_DP<13>")
		)
		(pad "2" smd rect
			(at 0.2667 0 270)
			(size 0.3048 0.381)
			(layers "F.Cu" "F.Mask" "F.Paste")
			(net "P5E_CPU0_P0_TX_BUF_DP<13>")
		)
	)
)
